(kicad_pcb
	(version 20260206)
	(generator "pcbnew")
	(generator_version "10.0")
	(general
		(thickness 1.6)
		(legacy_teardrops no)
	)
	(paper "A4")
	(title_block
		(title "Wiwynn_Tioga_Pass_MB.brd")
		(comment 1 "Tioga Pass / footprints 2506-2513 of 4770")
	)
	(layers
		(0 "F.Cu" signal "TOP")
		(4 "In1.Cu" signal "L2GND")
		(6 "In2.Cu" signal "L3")
		(8 "In3.Cu" signal "L4GND")
		(10 "In4.Cu" signal "L5")
		(12 "In5.Cu" signal "L6GND")
		(14 "In6.Cu" signal "L7VCC")
		(16 "In7.Cu" signal "L8VCC")
		(18 "In8.Cu" signal "L9GND")
		(20 "In9.Cu" signal "L10")
		(22 "In10.Cu" signal "L11GND")
		(24 "In11.Cu" signal "L12")
		(26 "In12.Cu" signal "L13GND")
		(2 "B.Cu" signal "BOTTOM")
		(9 "F.Adhes" user "F.Adhesive")
		(11 "B.Adhes" user "B.Adhesive")
		(13 "F.Paste" user "Package Geometry/Pastemask Top")
		(15 "B.Paste" user "Package Geometry/Pastemask Bottom")
		(5 "F.SilkS" user "Ref Des/Silkscreen Top")
		(7 "B.SilkS" user "Ref Des/Silkscreen Bottom")
		(1 "F.Mask" user "Board Geometry/Soldermask Top")
		(3 "B.Mask" user "Board Geometry/Soldermask Bottom")
		(17 "Dwgs.User" user "User.Drawings")
		(19 "Cmts.User" user "User.Comments")
		(21 "Eco1.User" user "User.Eco1")
		(23 "Eco2.User" user "User.Eco2")
		(25 "Edge.Cuts" user "Board Geometry/Outline")
		(27 "Margin" user)
		(31 "F.CrtYd" user "Package Geometry/Place Bound Top")
		(29 "B.CrtYd" user "Package Geometry/Place Bound Bottom")
		(35 "F.Fab" user "Ref Des/Assembly Top")
		(33 "B.Fab" user "Ref Des/Assembly Bottom")
	)
	(footprint ""
		(layer "B.Cu")
		(at 391.73785 -111.05515 180)
		(property "Reference" "C2N2"
			(at 0 0 0)
			(layer "B.SilkS")
			(hide yes)
			(effects
				(font
					(size 1.27 1.27)
				)
				(justify mirror)
			)
		)
		(property "Value" ""
			(at 0 0 0)
			(layer "B.Fab")
			(effects
				(font
					(size 1.27 1.27)
				)
				(justify mirror)
			)
		)
		(duplicate_pad_numbers_are_jumpers no)
		(fp_rect
			(start 0.2794 0.9144)
			(end -0.2794 -0.1143)
			(stroke
				(width 0)
				(type default)
			)
			(fill no)
			(layer "B.CrtYd")
		)
		(fp_line
			(start 0.2794 0.9144)
			(end 0.2794 -0.1143)
			(stroke
				(width 0.1)
				(type default)
			)
			(layer "B.Fab")
		)
		(fp_line
			(start 0.2794 -0.1143)
			(end -0.2794 -0.1143)
			(stroke
				(width 0.1)
				(type default)
			)
			(layer "B.Fab")
		)
		(fp_line
			(start -0.2794 0.9144)
			(end 0.2794 0.9144)
			(stroke
				(width 0.1)
				(type default)
			)
			(layer "B.Fab")
		)
		(fp_line
			(start -0.2794 -0.1143)
			(end -0.2794 0.9144)
			(stroke
				(width 0.1)
				(type default)
			)
			(layer "B.Fab")
		)
		(pad "1" smd custom
			(at 0 0 90)
			(size 0.10414 0.10414)
			(layers "B.Cu" "B.Mask" "B.Paste")
			(net "P1V05_PCH_STBY")
			(options
				(clearance outline)
				(anchor circle)
			)
			(primitives
				(gr_poly
					(pts
						(xy -0.20828 -0.08636) (xy -0.20828 0.08636) (xy -0.08636 0.20828) (xy 0.086614 0.20828) (xy 0.20828 0.086614)
						(xy 0.20828 -0.08636) (xy 0.08636 -0.20828) (xy -0.08636 -0.20828)
					)
					(width 0)
					(fill yes)
				)
			)
		)
		(pad "2" smd custom
			(at 0 0.8001 90)
			(size 0.10414 0.10414)
			(layers "B.Cu" "B.Mask" "B.Paste")
			(net "GND")
			(options
				(clearance outline)
				(anchor circle)
			)
			(primitives
				(gr_poly
					(pts
						(xy -0.20828 -0.08636) (xy -0.20828 0.08636) (xy -0.08636 0.20828) (xy 0.086614 0.20828) (xy 0.20828 0.086614)
						(xy 0.20828 -0.08636) (xy 0.08636 -0.20828) (xy -0.08636 -0.20828)
					)
					(width 0)
					(fill yes)
				)
			)
		)
		(zone
			(layer "B.Cu")
			(hatch none 0.5)
			(connect_pads
				(clearance 0)
			)
			(min_thickness 0.25)
			(keepout
				(tracks not_allowed)
				(vias allowed)
				(pads allowed)
				(copperpour not_allowed)
				(footprints allowed)
			)
			(placement
				(enabled no)
				(sheetname "")
			)
			(fill
				(thermal_gap 0.5)
				(thermal_bridge_width 0.5)
				(island_removal_mode 0)
			)
			(polygon
				(pts
					(xy 391.65022 -111.2647) (xy 391.65022 -111.6457) (xy 391.82548 -111.6457) (xy 391.825734 -111.2647)
				)
			)
		)
		(zone
			(layer "B.Cu")
			(hatch none 0.5)
			(connect_pads
				(clearance 0)
			)
			(min_thickness 0.25)
			(keepout
				(tracks allowed)
				(vias not_allowed)
				(pads allowed)
				(copperpour not_allowed)
				(footprints allowed)
			)
			(placement
				(enabled no)
				(sheetname "")
			)
			(fill
				(thermal_gap 0.5)
				(thermal_bridge_width 0.5)
				(island_removal_mode 0)
			)
			(polygon
				(pts
					(xy 391.65022 -111.2647) (xy 391.65022 -111.6457) (xy 391.82548 -111.6457) (xy 391.825734 -111.2647)
				)
			)
		)
	)
	(footprint ""
		(layer "B.Cu")
		(at 370.334794 -68.048632)
		(property "Reference" "R1W28"
			(at 0.8382 -0.67818 0)
			(unlocked yes)
			(layer "B.SilkS")
			(effects
				(font
					(size 0.4064 0.254)
					(thickness 0.1524)
				)
				(justify left mirror)
			)
		)
		(property "Value" ""
			(at 0 0 0)
			(layer "B.Fab")
			(effects
				(font
					(size 1.27 1.27)
				)
				(justify mirror)
			)
		)
		(duplicate_pad_numbers_are_jumpers no)
		(fp_poly
			(pts
				(xy 0.2794 -0.1016) (xy -0.2794 -0.1016) (xy -0.2794 0.9906) (xy 0.2794 0.9906)
			)
			(stroke
				(width 0)
				(type default)
			)
			(fill no)
			(layer "B.CrtYd")
		)
		(fp_line
			(start -0.2794 -0.1016)
			(end 0.2794 -0.1016)
			(stroke
				(width 0.1)
				(type default)
			)
			(layer "B.Fab")
		)
		(fp_line
			(start -0.2794 0.9906)
			(end -0.2794 -0.1016)
			(stroke
				(width 0.1)
				(type default)
			)
			(layer "B.Fab")
		)
		(fp_line
			(start 0.2794 -0.1016)
			(end 0.2794 0.9906)
			(stroke
				(width 0.1)
				(type default)
			)
			(layer "B.Fab")
		)
		(fp_line
			(start 0.2794 0.9906)
			(end -0.2794 0.9906)
			(stroke
				(width 0.1)
				(type default)
			)
			(layer "B.Fab")
		)
		(pad "1" smd rect
			(at 0 0 180)
			(size 0.508 0.508)
			(layers "B.Cu" "B.Mask" "B.Paste")
			(net "FM_PCH_PWRBTN_R1_N")
		)
		(pad "2" smd rect
			(at 0 0.889 180)
			(size 0.508 0.508)
			(layers "B.Cu" "B.Mask" "B.Paste")
			(net "FM_PCH_PWRBTN_N")
		)
		(zone
			(layer "B.Cu")
			(hatch none 0.5)
			(connect_pads
				(clearance 0)
			)
			(min_thickness 0.25)
			(keepout
				(tracks allowed)
				(vias not_allowed)
				(pads allowed)
				(copperpour not_allowed)
				(footprints allowed)
			)
			(placement
				(enabled no)
				(sheetname "")
			)
			(fill
				(thermal_gap 0.5)
				(thermal_bridge_width 0.5)
				(island_removal_mode 0)
			)
			(polygon
				(pts
					(xy 370.588794 -67.794632) (xy 370.080794 -67.794632) (xy 370.080794 -67.413632) (xy 370.588794 -67.413632)
				)
			)
		)
		(zone
			(layer "B.Cu")
			(hatch none 0.5)
			(connect_pads
				(clearance 0)
			)
			(min_thickness 0.25)
			(keepout
				(tracks not_allowed)
				(vias allowed)
				(pads allowed)
				(copperpour not_allowed)
				(footprints allowed)
			)
			(placement
				(enabled no)
				(sheetname "")
			)
			(fill
				(thermal_gap 0.5)
				(thermal_bridge_width 0.5)
				(island_removal_mode 0)
			)
			(polygon
				(pts
					(xy 370.588794 -67.413632) (xy 370.080794 -67.413632) (xy 370.080794 -67.794632) (xy 370.588794 -67.794632)
				)
			)
		)
	)
	(footprint ""
		(layer "B.Cu")
		(at 280.354024 -71.841614 180)
		(property "Reference" "C4P8"
			(at 0 0 0)
			(layer "B.SilkS")
			(hide yes)
			(effects
				(font
					(size 1.27 1.27)
				)
				(justify mirror)
			)
		)
		(property "Value" ""
			(at 0 0 0)
			(layer "B.Fab")
			(effects
				(font
					(size 1.27 1.27)
				)
				(justify mirror)
			)
		)
		(duplicate_pad_numbers_are_jumpers no)
		(fp_poly
			(pts
				(xy 0.4953 -0.2032) (xy -0.4953 -0.2032) (xy -0.4953 1.6002) (xy 0.4953 1.6002)
			)
			(stroke
				(width 0)
				(type default)
			)
			(fill no)
			(layer "B.CrtYd")
		)
		(fp_line
			(start 0.4953 1.6002)
			(end 0.4953 -0.2032)
			(stroke
				(width 0.1)
				(type default)
			)
			(layer "B.Fab")
		)
		(fp_line
			(start 0.4953 -0.2032)
			(end -0.4953 -0.2032)
			(stroke
				(width 0.1)
				(type default)
			)
			(layer "B.Fab")
		)
		(fp_line
			(start -0.4953 1.6002)
			(end 0.4953 1.6002)
			(stroke
				(width 0.1)
				(type default)
			)
			(layer "B.Fab")
		)
		(fp_line
			(start -0.4953 -0.2032)
			(end -0.4953 1.6002)
			(stroke
				(width 0.1)
				(type default)
			)
			(layer "B.Fab")
		)
		(pad "1" smd rect
			(at 0 0)
			(size 0.762 0.889)
			(layers "B.Cu" "B.Mask" "B.Paste")
			(net "PVCCIO_CPU0")
		)
		(pad "2" smd rect
			(at 0 1.397)
			(size 0.762 0.889)
			(layers "B.Cu" "B.Mask" "B.Paste")
			(net "GND")
		)
		(zone
			(layer "B.Cu")
			(hatch none 0.5)
			(connect_pads
				(clearance 0)
			)
			(min_thickness 0.25)
			(keepout
				(tracks not_allowed)
				(vias allowed)
				(pads allowed)
				(copperpour not_allowed)
				(footprints allowed)
			)
			(placement
				(enabled no)
				(sheetname "")
			)
			(fill
				(thermal_gap 0.5)
				(thermal_bridge_width 0.5)
				(island_removal_mode 0)
			)
			(polygon
				(pts
					(xy 279.973024 -72.286114) (xy 280.735024 -72.286114) (xy 280.735024 -72.794114) (xy 279.973024 -72.794114)
				)
			)
		)
	)
	(footprint ""
		(layer "B.Cu")
		(at 457.6064 -144.145 90)
		(property "Reference" "C1L11"
			(at 0 0 90)
			(layer "B.SilkS")
			(hide yes)
			(effects
				(font
					(size 1.27 1.27)
				)
				(justify mirror)
			)
		)
		(property "Value" ""
			(at 0 0 90)
			(layer "B.Fab")
			(effects
				(font
					(size 1.27 1.27)
				)
				(justify mirror)
			)
		)
		(duplicate_pad_numbers_are_jumpers no)
		(fp_poly
			(pts
				(xy -0.3048 -0.1016) (xy -0.3048 0.9906) (xy 0.3048 0.9906) (xy 0.3048 -0.1016)
			)
			(stroke
				(width 0)
				(type default)
			)
			(fill no)
			(layer "B.CrtYd")
		)
		(fp_line
			(start 0.3048 -0.1016)
			(end 0.3048 0.9906)
			(stroke
				(width 0.1)
				(type default)
			)
			(layer "B.Fab")
		)
		(fp_line
			(start -0.3048 -0.1016)
			(end 0.3048 -0.1016)
			(stroke
				(width 0.1)
				(type default)
			)
			(layer "B.Fab")
		)
		(fp_line
			(start 0.3048 0.9906)
			(end -0.3048 0.9906)
			(stroke
				(width 0.1)
				(type default)
			)
			(layer "B.Fab")
		)
		(fp_line
			(start -0.3048 0.9906)
			(end -0.3048 -0.1016)
			(stroke
				(width 0.1)
				(type default)
			)
			(layer "B.Fab")
		)
		(pad "1" smd rect
			(at 0 0 270)
			(size 0.508 0.508)
			(layers "B.Cu" "B.Mask" "B.Paste")
			(net "P3V3_STBY")
		)
		(pad "2" smd rect
			(at 0 0.889 270)
			(size 0.508 0.508)
			(layers "B.Cu" "B.Mask" "B.Paste")
			(net "GND")
		)
		(zone
			(layer "B.Cu")
			(hatch none 0.5)
			(connect_pads
				(clearance 0)
			)
			(min_thickness 0.25)
			(keepout
				(tracks allowed)
				(vias not_allowed)
				(pads allowed)
				(copperpour not_allowed)
				(footprints allowed)
			)
			(placement
				(enabled no)
				(sheetname "")
			)
			(fill
				(thermal_gap 0.5)
				(thermal_bridge_width 0.5)
				(island_removal_mode 0)
			)
			(polygon
				(pts
					(xy 457.8604 -144.399) (xy 457.8604 -143.891) (xy 458.2414 -143.891) (xy 458.2414 -144.399)
				)
			)
		)
		(zone
			(layer "B.Cu")
			(hatch none 0.5)
			(connect_pads
				(clearance 0)
			)
			(min_thickness 0.25)
			(keepout
				(tracks not_allowed)
				(vias allowed)
				(pads allowed)
				(copperpour not_allowed)
				(footprints allowed)
			)
			(placement
				(enabled no)
				(sheetname "")
			)
			(fill
				(thermal_gap 0.5)
				(thermal_bridge_width 0.5)
				(island_removal_mode 0)
			)
			(polygon
				(pts
					(xy 458.2414 -144.399) (xy 458.2414 -143.891) (xy 457.8604 -143.891) (xy 457.8604 -144.399)
				)
			)
		)
	)
	(footprint ""
		(layer "B.Cu")
		(at 101.244654 -79.60614 180)
		(property "Reference" "C8P11"
			(at 0 0 0)
			(layer "B.SilkS")
			(hide yes)
			(effects
				(font
					(size 1.27 1.27)
				)
				(justify mirror)
			)
		)
		(property "Value" ""
			(at 0 0 0)
			(layer "B.Fab")
			(effects
				(font
					(size 1.27 1.27)
				)
				(justify mirror)
			)
		)
		(duplicate_pad_numbers_are_jumpers no)
		(fp_poly
			(pts
				(xy 0.7239 -0.2159) (xy -0.7239 -0.2159) (xy -0.7239 1.9939) (xy 0.7239 1.9939)
			)
			(stroke
				(width 0)
				(type default)
			)
			(fill no)
			(layer "B.CrtYd")
		)
		(fp_line
			(start 0.7239 1.9939)
			(end -0.7239 1.9939)
			(stroke
				(width 0.1)
				(type default)
			)
			(layer "B.Fab")
		)
		(fp_line
			(start 0.7239 -0.2159)
			(end 0.7239 1.9939)
			(stroke
				(width 0.1)
				(type default)
			)
			(layer "B.Fab")
		)
		(fp_line
			(start -0.7239 1.9939)
			(end -0.7239 -0.2159)
			(stroke
				(width 0.1)
				(type default)
			)
			(layer "B.Fab")
		)
		(fp_line
			(start -0.7239 -0.2159)
			(end 0.7239 -0.2159)
			(stroke
				(width 0.1)
				(type default)
			)
			(layer "B.Fab")
		)
		(pad "1" smd rect
			(at 0 0)
			(size 1.27 1.016)
			(layers "B.Cu" "B.Mask" "B.Paste")
			(net "PVCCIN_CPU1")
		)
		(pad "2" smd rect
			(at 0 1.778)
			(size 1.27 1.016)
			(layers "B.Cu" "B.Mask" "B.Paste")
			(net "GND")
		)
		(zone
			(layer "B.Cu")
			(hatch none 0.5)
			(connect_pads
				(clearance 0)
			)
			(min_thickness 0.25)
			(keepout
				(tracks not_allowed)
				(vias allowed)
				(pads allowed)
				(copperpour not_allowed)
				(footprints allowed)
			)
			(placement
				(enabled no)
				(sheetname "")
			)
			(fill
				(thermal_gap 0.5)
				(thermal_bridge_width 0.5)
				(island_removal_mode 0)
			)
			(polygon
				(pts
					(xy 100.609654 -80.11414) (xy 101.879654 -80.11414) (xy 101.879654 -80.87614) (xy 100.609654 -80.87614)
				)
			)
		)
	)
	(footprint ""
		(layer "B.Cu")
		(at 197.239128 -54.531006 90)
		(property "Reference" "R6R2"
			(at 0 0 90)
			(layer "B.SilkS")
			(hide yes)
			(effects
				(font
					(size 1.27 1.27)
				)
				(justify mirror)
			)
		)
		(property "Value" ""
			(at 0 0 90)
			(layer "B.Fab")
			(effects
				(font
					(size 1.27 1.27)
				)
				(justify mirror)
			)
		)
		(duplicate_pad_numbers_are_jumpers no)
		(fp_rect
			(start 0.2794 -0.1016)
			(end -0.2794 0.9906)
			(stroke
				(width 0)
				(type default)
			)
			(fill no)
			(layer "B.CrtYd")
		)
		(fp_line
			(start 0.2794 -0.1016)
			(end 0.2794 0.9906)
			(stroke
				(width 0.1)
				(type default)
			)
			(layer "B.Fab")
		)
		(fp_line
			(start -0.2794 -0.1016)
			(end 0.2794 -0.1016)
			(stroke
				(width 0.1)
				(type default)
			)
			(layer "B.Fab")
		)
		(fp_line
			(start 0.2794 0.9906)
			(end -0.2794 0.9906)
			(stroke
				(width 0.1)
				(type default)
			)
			(layer "B.Fab")
		)
		(fp_line
			(start -0.2794 0.9906)
			(end -0.2794 -0.1016)
			(stroke
				(width 0.1)
				(type default)
			)
			(layer "B.Fab")
		)
		(pad "1" smd rect
			(at 0 0 270)
			(size 0.508 0.508)
			(layers "B.Cu" "B.Mask" "B.Paste")
			(net "VR_PVCCIN_CPU0_PH1_VCIN")
		)
		(pad "2" smd rect
			(at 0 0.889 270)
			(size 0.508 0.508)
			(layers "B.Cu" "B.Mask" "B.Paste")
			(net "P5V_STBY")
		)
		(zone
			(layer "B.Cu")
			(hatch none 0.5)
			(connect_pads
				(clearance 0)
			)
			(min_thickness 0.25)
			(keepout
				(tracks allowed)
				(vias not_allowed)
				(pads allowed)
				(copperpour not_allowed)
				(footprints allowed)
			)
			(placement
				(enabled no)
				(sheetname "")
			)
			(fill
				(thermal_gap 0.5)
				(thermal_bridge_width 0.5)
				(island_removal_mode 0)
			)
			(polygon
				(pts
					(xy 197.493128 -54.785006) (xy 197.493128 -54.277006) (xy 197.874128 -54.277006) (xy 197.874128 -54.785006)
				)
			)
		)
		(zone
			(layer "B.Cu")
			(hatch none 0.5)
			(connect_pads
				(clearance 0)
			)
			(min_thickness 0.25)
			(keepout
				(tracks not_allowed)
				(vias allowed)
				(pads allowed)
				(copperpour not_allowed)
				(footprints allowed)
			)
			(placement
				(enabled no)
				(sheetname "")
			)
			(fill
				(thermal_gap 0.5)
				(thermal_bridge_width 0.5)
				(island_removal_mode 0)
			)
			(polygon
				(pts
					(xy 197.493128 -54.785006) (xy 197.493128 -54.277006) (xy 197.874128 -54.277006) (xy 197.874128 -54.785006)
				)
			)
		)
	)
	(footprint ""
		(layer "B.Cu")
		(at 166.751 4.445 180)
		(property "Reference" "R6U17"
			(at 0 0 0)
			(layer "B.SilkS")
			(hide yes)
			(effects
				(font
					(size 1.27 1.27)
				)
				(justify mirror)
			)
		)
		(property "Value" ""
			(at 0 0 0)
			(layer "B.Fab")
			(effects
				(font
					(size 1.27 1.27)
				)
				(justify mirror)
			)
		)
		(duplicate_pad_numbers_are_jumpers no)
		(fp_poly
			(pts
				(xy 0.2794 -0.1016) (xy -0.2794 -0.1016) (xy -0.2794 0.9906) (xy 0.2794 0.9906)
			)
			(stroke
				(width 0)
				(type default)
			)
			(fill no)
			(layer "B.CrtYd")
		)
		(fp_line
			(start 0.2794 0.9906)
			(end -0.2794 0.9906)
			(stroke
				(width 0.1)
				(type default)
			)
			(layer "B.Fab")
		)
		(fp_line
			(start 0.2794 -0.1016)
			(end 0.2794 0.9906)
			(stroke
				(width 0.1)
				(type default)
			)
			(layer "B.Fab")
		)
		(fp_line
			(start -0.2794 0.9906)
			(end -0.2794 -0.1016)
			(stroke
				(width 0.1)
				(type default)
			)
			(layer "B.Fab")
		)
		(fp_line
			(start -0.2794 -0.1016)
			(end 0.2794 -0.1016)
			(stroke
				(width 0.1)
				(type default)
			)
			(layer "B.Fab")
		)
		(pad "1" smd rect
			(at 0 0)
			(size 0.508 0.508)
			(layers "B.Cu" "B.Mask" "B.Paste")
			(net "PVPP_GHJ")
		)
		(pad "2" smd rect
			(at 0 0.889)
			(size 0.508 0.508)
			(layers "B.Cu" "B.Mask" "B.Paste")
			(net "SMB_DDR_GHJ_VPP_SCL_R")
		)
		(zone
			(layer "B.Cu")
			(hatch none 0.5)
			(connect_pads
				(clearance 0)
			)
			(min_thickness 0.25)
			(keepout
				(tracks not_allowed)
				(vias allowed)
				(pads allowed)
				(copperpour not_allowed)
				(footprints allowed)
			)
			(placement
				(enabled no)
				(sheetname "")
			)
			(fill
				(thermal_gap 0.5)
				(thermal_bridge_width 0.5)
				(island_removal_mode 0)
			)
			(polygon
				(pts
					(xy 166.497 3.81) (xy 167.005 3.81) (xy 167.005 4.191) (xy 166.497 4.191)
				)
			)
		)
		(zone
			(layer "B.Cu")
			(hatch none 0.5)
			(connect_pads
				(clearance 0)
			)
			(min_thickness 0.25)
			(keepout
				(tracks allowed)
				(vias not_allowed)
				(pads allowed)
				(copperpour not_allowed)
				(footprints allowed)
			)
			(placement
				(enabled no)
				(sheetname "")
			)
			(fill
				(thermal_gap 0.5)
				(thermal_bridge_width 0.5)
				(island_removal_mode 0)
			)
			(polygon
				(pts
					(xy 166.497 4.191) (xy 167.005 4.191) (xy 167.005 3.81) (xy 166.497 3.81)
				)
			)
		)
	)
	(footprint ""
		(layer "B.Cu")
		(at 355.3333 -146.82724)
		(property "Reference" "C7W9"
			(at 0 0 0)
			(layer "B.SilkS")
			(hide yes)
			(effects
				(font
					(size 1.27 1.27)
				)
				(justify mirror)
			)
		)
		(property "Value" "*"
			(at 0.0762 -6.2357 0)
			(unlocked yes)
			(layer "B.Fab")
			(hide yes)
			(effects
				(font
					(size 1.27 1.016)
					(thickness 0.1524)
				)
				(justify mirror)
			)
		)
		(property "Device Type" "SC22U16V5MX-4-GP_SMD-BCG5-SC22A"
			(at 0.0762 -8.2677 0)
			(unlocked yes)
			(layer "B.Fab")
			(hide yes)
			(effects
				(font
					(size 1.27 1.016)
					(thickness 0.1524)
				)
				(justify mirror)
			)
		)
		(duplicate_pad_numbers_are_jumpers no)
		(fp_line
			(start -0.635 0)
			(end 0.635 0)
			(stroke
				(width 0.508)
				(type default)
			)
			(layer "B.SilkS")
		)
		(fp_rect
			(start 0.9652 1.778)
			(end -0.9652 -1.778)
			(stroke
				(width 0)
				(type default)
			)
			(fill no)
			(layer "B.CrtYd")
		)
		(fp_poly
			(pts
				(xy 0.9652 -1.778) (xy -0.9652 -1.778) (xy -0.9652 1.778) (xy 0.9652 1.778)
			)
			(stroke
				(width 0)
				(type default)
			)
			(fill no)
			(layer "B.Fab")
		)
		(pad "1" smd rect
			(at 0 -0.9652 180)
			(size 1.397 1.143)
			(layers "B.Cu" "B.Mask" "B.Paste")
			(net "VR_FET_SW_P12V_STBY_PVDDQ_DEF")
		)
		(pad "2" smd rect
			(at 0 0.9652 180)
			(size 1.397 1.143)
			(layers "B.Cu" "B.Mask" "B.Paste")
			(net "GND")
		)
	)
)
